FILE_TYPE = MULTI_PHYS_TABLE;
PART 'MIC5166'
{==============================================================================================================================================================}
:PACK_TYPE | MATERIAL | PART_NUMBER     = EnvComp |  PART_NUMBER | JEDEC_TYPE      | CLASS | DESCRIPTION                   | HEIGHT     | COMPONENT_TYPE | LPID     | SPEED_URL | Status |RPL| AML | Bus_Unit | Days ;
{==============================================================================================================================================================}
'DFN'      | 'IC'     | 'H55101-001'(!) = ''      | 'H55101-001' | 'DFN10_12_50MF' | 'IC'  | 'IC,LIN,MLF,MIC5166,VREG'     | '0.035 IN' | 'LCC'          | '3373' | 'http://speed.intel.com:8081/speed/module/pdm/item/pdm_item_detail_direct.asp?item_cde=H55101-001&item_rev=01&url_param=unused' | '' | '' | '' | '' | '' 
'DFN'      | 'EMPTY'  | 'H55101-001'(!) = ''      | 'H55101-001' | 'DFN10_12_50MF' | 'IO'  | 'IC,LIN,MLF,MIC5166,VREG'     | '0.035 IN' | 'LCC'          | '3373' | 'http://speed.intel.com:8081/speed/module/pdm/item/pdm_item_detail_direct.asp?item_cde=H55101-001&item_rev=01&url_param=unused' | '' | '' | '' | '' | '' 
END_PART
END.
